FILE_TYPE=LIBRARY_PARTS;
primitive 'TUSB211IRWBR';
  pin
    'RSTN':
      PIN_NUMBER='(5)';
      INPUT_LOAD='(-0.01,0.01)';
    'D2M':
      PIN_NUMBER='(8)';
      BIDIRECTIONAL='TRUE';
      INPUT_LOAD='(-0.01,0.01)';
      OUTPUT_LOAD='(1.0,-1.0)';
    'VREG':
      PIN_NUMBER='(11)';
      OUTPUT_LOAD='(1.0,-1.0)';
    'TEST':
      PIN_NUMBER='(3)';
      INPUT_LOAD='(-0.01,0.01)';
    'VCC':
      PIN_NUMBER='(12)';
      PINUSE='POWER';
      NO_LOAD_CHECK='Both';
      NO_IO_CHECK='Both';
      NO_ASSERT_CHECK='TRUE';
      NO_DIR_CHECK='TRUE';
      ALLOW_CONNECT='TRUE';
    'ENA_HS':
      PIN_NUMBER='(9)';
      OUTPUT_LOAD='(1.0,-1.0)';
    'CD':
      PIN_NUMBER='(4)';
      OUTPUT_LOAD='(1.0,-1.0)';
    'D1M':
      PIN_NUMBER='(1)';
      BIDIRECTIONAL='TRUE';
      INPUT_LOAD='(-0.01,0.01)';
      OUTPUT_LOAD='(1.0,-1.0)';
    'D1P':
      PIN_NUMBER='(2)';
      BIDIRECTIONAL='TRUE';
      INPUT_LOAD='(-0.01,0.01)';
      OUTPUT_LOAD='(1.0,-1.0)';
    'D2P':
      PIN_NUMBER='(7)';
      BIDIRECTIONAL='TRUE';
      INPUT_LOAD='(-0.01,0.01)';
      OUTPUT_LOAD='(1.0,-1.0)';
    'EQ':
      PIN_NUMBER='(6)';
      INPUT_LOAD='(-0.01,0.01)';
    'GND':
      PIN_NUMBER='(10)';
      PINUSE='POWER';
      NO_LOAD_CHECK='Both';
      NO_IO_CHECK='Both';
      NO_ASSERT_CHECK='TRUE';
      NO_DIR_CHECK='TRUE';
      ALLOW_CONNECT='TRUE';
  end_pin;
  body
    PART_NAME='TUSB211IRWBR';
    BODY_NAME='TUSB211IRWBR';
    PHYS_DES_PREFIX='U';
    CLASS='IC';
  end_body;
end_primitive;

END.
